FILE_TYPE = CONNECTIVITY;
{Allegro Design Entry HDL 17.2-2016 S081 (4005846) 1/11/2022}
"PAGE_NUMBER" = 324;
0"NC";
1"P12V_AUX\g";
2"P3V3_AUX\g";
3"P12V_AUX\g";
4"P12V_AUX\g";
5"P3V3_AUX\g";
6"P3V3_E1S_0_R\g";
7"P3V3_AUX\g";
8"P12V_E1S_0\g";
9"GND\g";
10"GND\g";
11"GND\g";
12"GND\g";
13"GND\g";
14"GND\g";
15"GND\g";
16"GND\g";
17"GND\g";
18"GND\g";
19"GND\g";
20"GND\g";
21"GND\g";
22"GND\g";
23"GND\g";
24"GND\g";
25"GND\g";
26"GND\g";
27"GND\g";
28"P12V_E1S_OV_0";
29"P12V_E1S_UV_0";
30"P12V_E1S_0_ISENSE_MAM_TIC";
31"P12V_E1S_0_ISENSE_MAM_MAM";
32"HP_LVC3_E1S_0_HSC_PWRGD";
33"P12V_E1S_SENSE_0";
34"P12V_E1S_GATE_0";
35"P12V_E1S_PWRGD_0";
36"P12V_E1S_FAULT_0";
37"P12V_E1S_REG_0";
38"P12V_E1S_VCC_0";
39"P12V_E1S_CB_0";
40"TP_P3V3_E1S_PWRGD_0";
41"P3V3_E1S_GATE_0";
42"P3V3_E1S_PWRGD_0";
43"P3V3_E1S_SENSE_0";
44"P3V3_E1S_FAULT_0";
45"P3V3_E1S_REG_0";
46"P3V3_E1S_VCC_0";
47"P3V3_E1S_OV_0";
48"P3V3_E1S_CB_0";
49"P12V_E1S_UV_0_R";
50"P12V_E1S_0_EN_G";
51"P12V_E1S_EN_0_R";
52"E1S_0_EN";
53"P3V3_E1S_UV_0";
54"P3V3_E1S_UV_0_R";
55"P3V3_E1S_0_EN_G";
56"P3V3_E1S_EN_1_R";
%"Q_RES"
"1","(-4100,-2400)","0","pure_quanta","I1";
;
PART_NUMBER"CS00002JB13"
TOLERANCE"5%"
VALUE"0"
PACK_TYPE"0402LF"
MATERIAL"CHIP"
WATTAGE"1/16W"
ROOM"E1S1_P3V3_BOM1"
$LOCATION"R4063"
CDS_LIB"pure_quanta"
CDS_LOCATION"R4063"
$SEC"1"
CDS_SEC"1";
"B"
$PN"2"56;
"A"
$PN"1"52;
%"MOSFET_NCH_DUAL"
"1","(-2575,150)","0","pure_quanta","I10";
;
PART_NUMBER"BAM138K0003"
MATERIAL"EMPTY"
VALUE"PJT138K"
PART_TYPE"SMLF"
ROOM"E1S1_P12V_MAM_MAM_BOM1"
$LOCATION"Q127"
NEEDS_NO_SIZE"TRUE"
CDS_LMAN_SYM_OUTLINE"-150,150,150,-150"
CDS_LIB"pure_quanta"
ROOM1"E1S1_P12V_MAM_TIC_BOM2"
CDS_LOCATION"Q127"
$SEC"1"
CDS_SEC"1";
"D1"
$PN"6"50;
"G1"
$PN"2"51;
"S1"
$PN"1"12;
%"GND"
"1","(-2525,-200)","0","logical_power","I11";
;
CDS_LIB"logical_power"
SIZE"1B"
HDL_POWER"GND";
"A<SIZE-1..0>\NAC"12;
%"GND"
"1","(-125,-2600)","0","logical_power","I12";
;
CDS_LIB"logical_power"
SIZE"1B"
HDL_POWER"GND";
"A<SIZE-1..0>\NAC"13;
%"Q_RES"
"2","(-125,-2350)","0","pure_quanta","I13";
;
PART_NUMBER"CS31502FB05"
TOLERANCE"1%"
VALUE"15K"
PACK_TYPE"0402LF"
WATTAGE"1/16W"
MATERIAL"CHIP"
ROOM"E1S1_P3V3_BOM1"
LOCATION"PR3965"
CDS_LIB"pure_quanta"
$SEC"1"
CDS_SEC"1";
"A"
$PN"1"47;
"B"
$PN"2"13;
%"Q_RES"
"2","(-125,-2075)","0","pure_quanta","I14";
;
PART_NUMBER"CS27152FB03"
TOLERANCE"1%"
MATERIAL"CHIP"
PACK_TYPE"0402LF"
WATTAGE"1/16W"
VALUE"7.15K"
ROOM"E1S1_P3V3_BOM1"
LOCATION"PR3964"
CDS_LIB"pure_quanta"
$SEC"1"
CDS_SEC"1";
"A"
$PN"1"53;
"B"
$PN"2"47;
%"Q_RES"
"1","(-600,-1725)","0","pure_quanta","I15";
;
PART_NUMBER"CS00002JB13"
WATTAGE"1/16W"
PACK_TYPE"0402LF"
ROOM"E1S1_P3V3_BOM1"
TOLERANCE"5%"
VALUE"0"
MATERIAL"CHIP"
$LOCATION"R3959"
CDS_LIB"pure_quanta"
CDS_LOCATION"R3959"
$SEC"1"
CDS_SEC"1";
"B"
$PN"2"53;
"A"
$PN"1"54;
%"GND"
"1","(-475,-1375)","0","logical_power","I16";
;
SIZE"1B"
CDS_LIB"logical_power"
HDL_POWER"GND";
"A<SIZE-1..0>\NAC"14;
%"Q_CAP"
"1","(-475,-1100)","0","pure_quanta","I17";
;
PART_NUMBER"CH5104KEB02"
VOLTAGE"25V"
VALUE"1UF"
MATERIAL"X6S"
PACK_TYPE"C0402"
ROOM"E1S1_P3V3_BOM1"
LOCATION"PC2208"
TOLERANCE"10%"
CDS_LIB"pure_quanta"
$SEC"1"
CDS_SEC"1";
"B"
$PN"2"14;
"A"
$PN"1"2;
%"Q_RES"
"2","(-125,-1350)","0","pure_quanta","I18";
;
PART_NUMBER"CS32552FB06"
MATERIAL"CHIP"
WATTAGE"1/16W"
TOLERANCE"1%"
VALUE"25.5K"
PACK_TYPE"0402LF"
ROOM"E1S1_P3V3_BOM1"
LOCATION"PR3963"
CDS_LIB"pure_quanta"
$SEC"1"
CDS_SEC"1";
"A"
$PN"1"2;
"B"
$PN"2"53;
%"UNIVERSAL_POWER"
"1","(-475,-750)","0","logical_power","I19";
;
HDL_POWER"P3V3_AUX"
CDS_LIB"logical_power";
"A"2;
%"GND"
"1","(-3150,-2725)","0","logical_power","I2";
;
CDS_LIB"logical_power"
SIZE"1B"
HDL_POWER"GND";
"A<SIZE-1..0>\NAC"9;
%"Q_RES"
"1","(-3400,100)","0","pure_quanta","I21";
;
PART_NUMBER"CS00002JB13"
MATERIAL"CHIP"
PACK_TYPE"0402LF"
WATTAGE"1/16W"
TOLERANCE"5%"
VALUE"0"
$LOCATION"R4064"
CDS_LIB"pure_quanta"
CDS_LOCATION"R4064"
$SEC"1"
CDS_SEC"1";
"B"
$PN"2"51;
"A"
$PN"1"52;
%"Q_RES"
"2","(-2525,750)","0","pure_quanta","I22";
;
PART_NUMBER"CS31002FB08"
ROOM"E1S1_P12V_MAM_MAM_BOM1"
TOLERANCE"1%"
VALUE"10K"
WATTAGE"1/16W"
PACK_TYPE"0402LF"
MATERIAL"EMPTY"
$LOCATION"R4074"
ROOM1"E1S1_P12V_MAM_TIC_BOM2"
CDS_LIB"pure_quanta"
CDS_LOCATION"R4074"
$SEC"1"
CDS_SEC"1";
"A"
$PN"1"3;
"B"
$PN"2"50;
%"UNIVERSAL_POWER"
"1","(-2525,1000)","0","logical_power","I23";
;
HDL_POWER"P12V_AUX"
CDS_LIB"logical_power";
"A"3;
%"MOSFET_NCH_DUAL"
"2","(-1875,525)","0","pure_quanta","I24";
;
PART_NUMBER"BAM138K0003"
MATERIAL"EMPTY"
VALUE"PJT138K"
PART_TYPE"SMLF"
ROOM"E1S1_P12V_MAM_MAM_BOM1"
$LOCATION"Q127"
ROOM1"E1S1_P12V_MAM_TIC_BOM2"
NEEDS_NO_SIZE"TRUE"
CDS_LMAN_SYM_OUTLINE"-150,150,150,-150"
CDS_LIB"pure_quanta"
CDS_LOCATION"Q127"
$SEC"2"
CDS_SEC"2";
"S2"
$PN"4"15;
"G2"
$PN"5"50;
"D2"
$PN"3"49;
%"GND"
"1","(-1825,175)","0","logical_power","I25";
;
CDS_LIB"logical_power"
SIZE"1B"
HDL_POWER"GND";
"A<SIZE-1..0>\NAC"15;
%"Q_RES"
"1","(-750,1000)","0","pure_quanta","I26";
;
PART_NUMBER"CS00002JB13"
WATTAGE"1/16W"
MATERIAL"EMPTY"
VALUE"0"
TOLERANCE"5%"
PACK_TYPE"0402LF"
ROOM"E1S1_P12V_MAM_MAM_BOM1"
$LOCATION"R3958"
ROOM1"E1S1_P12V_MAM_TIC_BOM2"
CDS_LIB"pure_quanta"
CDS_LOCATION"R3958"
$SEC"1"
CDS_SEC"1";
"B"
$PN"2"29;
"A"
$PN"1"49;
%"GND"
"1","(-150,125)","0","logical_power","I27";
;
CDS_LIB"logical_power"
SIZE"1B"
HDL_POWER"GND";
"A<SIZE-1..0>\NAC"16;
%"Q_RES"
"2","(-150,375)","0","pure_quanta","I28";
;
PART_NUMBER"CS31502FB05"
WATTAGE"1/16W"
TOLERANCE"1%"
VALUE"15K"
PACK_TYPE"0402LF"
ROOM"E1S1_P12V_MAM_MAM_BOM1"
MATERIAL"EMPTY"
LOCATION"PR3962"
ROOM1"E1S1_P12V_MAM_TIC_BOM2"
CDS_LIB"pure_quanta"
$SEC"1"
CDS_SEC"1";
"A"
$PN"1"28;
"B"
$PN"2"16;
%"GND"
"1","(-725,1250)","0","logical_power","I29";
;
SIZE"1B"
CDS_LIB"logical_power"
HDL_POWER"GND";
"A<SIZE-1..0>\NAC"17;
%"MOSFET_NCH_DUAL"
"1","(-3200,-2375)","0","pure_quanta","I3";
;
PART_NUMBER"BAM138K0003"
MATERIAL"IC"
ROOM"E1S1_P3V3_BOM1"
PART_TYPE"SMLF"
VALUE"PJT138K"
$LOCATION"Q126"
CDS_LIB"pure_quanta"
CDS_LMAN_SYM_OUTLINE"-150,150,150,-150"
NEEDS_NO_SIZE"TRUE"
CDS_LOCATION"Q126"
$SEC"1"
CDS_SEC"1";
"D1"
$PN"6"55;
"G1"
$PN"2"56;
"S1"
$PN"1"9;
%"UNIVERSAL_POWER"
"1","(-725,1975)","0","logical_power","I30";
;
HDL_POWER"P12V_AUX"
CDS_LIB"logical_power";
"A"4;
%"Q_CAP"
"1","(-500,1625)","0","pure_quanta","I31";
;
PART_NUMBER"CH5104KEB02"
PACK_TYPE"C0402"
VOLTAGE"25V"
VALUE"1UF"
MATERIAL"X6S"
LOCATION"PC2207"
CDS_LIB"pure_quanta"
TOLERANCE"10%"
$SEC"1"
CDS_SEC"1";
"B"
$PN"2"17;
"A"
$PN"1"4;
%"Q_RES"
"2","(-150,1325)","0","pure_quanta","I32";
;
PART_NUMBER"CS41602FB05"
VALUE"160K"
TOLERANCE"1%"
PACK_TYPE"0402LF"
MATERIAL"EMPTY"
WATTAGE"1/16W"
ROOM"E1S1_P12V_MAM_MAM_BOM1"
LOCATION"PR3960"
ROOM1"E1S1_P12V_MAM_TIC_BOM2"
CDS_LIB"pure_quanta"
$SEC"1"
CDS_SEC"1";
"A"
$PN"1"4;
"B"
$PN"2"29;
%"GND"
"1","(725,-2625)","0","logical_power","I33";
;
SIZE"1B"
CDS_LIB"logical_power"
HDL_POWER"GND";
"A<SIZE-1..0>\NAC"18;
%"Q_RES"
"2","(725,-2325)","0","pure_quanta","I34";
;
PART_NUMBER"CS22492FB05"
PACK_TYPE"0402LF"
TOLERANCE"1%"
MATERIAL"CHIP"
WATTAGE"1/16W"
VALUE"2.49K"
ROOM"E1S1_P3V3_BOM1"
LOCATION"PR3969"
CDS_LIB"pure_quanta"
$SEC"1"
CDS_SEC"1";
"A"
$PN"1"48;
"B"
$PN"2"18;
%"MAX15090BEWIT"
"1","(1475,-1825)","0","pure_quanta","I35";
;
PART_NUMBER"AL015080B00"
ROOM"E1S1_P3V3_BOM1"
VALUE"MAX15090BEWI+T"
PART_TYPE"SMLF"
MATERIAL"IC"
LOCATION"PU295"
PIN_NAMES_ROTATE"TRUE"
CDS_LIB"pure_quanta"
CDS_LMAN_SYM_OUTLINE"-250,550,250,-550"
$SEC"1"
CDS_SEC"1";
"PG"
$PN"D7"42;
"FAULT# \B"
$PN"C7"44;
"GND_C2"
$PN"C2"20;
"GND_C1"
$PN"C1"20;
"GND_B2"
$PN"B2"20;
"CDLY"
$PN"A7"20;
"GATE"
$PN"A6"41;
"OUT_D6"
$PN"D6"6;
"OUT_D4"
$PN"D4"6;
"OUT_C6"
$PN"C6"6;
"OUT_C4"
$PN"C4"6;
"OUT_B6"
$PN"B6"6;
"OUT_B4"
$PN"B4"6;
"OUT_A4"
$PN"A4"6;
"ISENSE"
$PN"A1"43;
"OV"
$PN"D3"47;
"UV"
$PN"D2"53;
"REG"
$PN"D1"45;
"EN# \B"
$PN"B7"18;
"CB"
$PN"B1"48;
"IN_D5"
$PN"D5"2;
"IN_C5"
$PN"C5"2;
"IN_C3"
$PN"C3"2;
"IN_B5"
$PN"B5"2;
"IN_B3"
$PN"B3"2;
"IN_A5"
$PN"A5"2;
"IN_A3"
$PN"A3"2;
"VCC"
$PN"A2"46;
%"GND"
"1","(200,-1900)","0","logical_power","I36";
;
SIZE"1B"
CDS_LIB"logical_power"
HDL_POWER"GND";
"A<SIZE-1..0>\NAC"19;
%"Q_CAP"
"1","(200,-1525)","0","pure_quanta","I37";
;
PART_NUMBER"CH5104KEB02"
MATERIAL"X6S"
VOLTAGE"25V"
PACK_TYPE"C0402"
VALUE"1UF"
ROOM"E1S1_P3V3_BOM1"
LOCATION"PC2210"
TOLERANCE"10%"
CDS_LIB"pure_quanta"
$SEC"1"
CDS_SEC"1";
"B"
$PN"2"19;
"A"
$PN"1"46;
%"Q_CAP"
"1","(425,-1825)","1","pure_quanta","I38";
;
PART_NUMBER"CH5104KEB02"
PACK_TYPE"C0402"
VOLTAGE"25V"
VALUE"1UF"
ROOM"E1S1_P3V3_BOM1"
LOCATION"PC2212"
TOLERANCE"10%"
MATERIAL"X6S"
CDS_LIB"pure_quanta"
$SEC"1"
CDS_SEC"1";
"B"
$PN"2"45;
"A"
$PN"1"19;
%"Q_RES"
"2","(200,-1100)","0","pure_quanta","I39";
;
PART_NUMBER"CS01002FB07"
TOLERANCE"1%"
WATTAGE"1/16W"
MATERIAL"CHIP"
PACK_TYPE"0402LF"
VALUE"10"
ROOM"E1S1_P3V3_BOM1"
LOCATION"PR3967"
CDS_LIB"pure_quanta"
$SEC"1"
CDS_SEC"1";
"A"
$PN"1"2;
"B"
$PN"2"46;
%"MOSFET_NCH_DUAL"
"2","(-2525,-2050)","0","pure_quanta","I4";
;
PART_NUMBER"BAM138K0003"
MATERIAL"IC"
ROOM"E1S1_P3V3_BOM1"
PART_TYPE"SMLF"
VALUE"PJT138K"
$LOCATION"Q126"
CDS_LIB"pure_quanta"
CDS_LMAN_SYM_OUTLINE"-150,150,150,-150"
NEEDS_NO_SIZE"TRUE"
CDS_LOCATION"Q126"
$SEC"2"
CDS_SEC"2";
"S2"
$PN"4"10;
"G2"
$PN"5"55;
"D2"
$PN"3"54;
%"GND"
"1","(2200,-2500)","0","logical_power","I40";
;
CDS_LIB"logical_power"
HDL_POWER"GND"
SIZE"1B";
"A<SIZE-1..0>\NAC"20;
%"Q_RES"
"2","(2325,-2175)","0","pure_quanta","I41";
;
PART_NUMBER"CS29762FB05"
PACK_TYPE"0402LF"
MATERIAL"CHIP"
VALUE"9.76K"
TOLERANCE"1%"
WATTAGE"1/16W"
ROOM"E1S1_P3V3_BOM1"
LOCATION"PR3971"
CDS_LIB"pure_quanta"
$SEC"1"
CDS_SEC"1";
"A"
$PN"1"43;
"B"
$PN"2"20;
%"Q_CAP"
"1","(2275,-1500)","0","pure_quanta","I42";
;
PART_NUMBER"CH31006KB18"
VALUE"0.01UF"
VOLTAGE"50V"
MATERIAL"EMPTY"
PACK_TYPE"C0402"
LOCATION"PC2213"
TOLERANCE"10%"
CDS_LIB"pure_quanta"
$SEC"1"
CDS_SEC"1";
"B"
$PN"2"41;
"A"
$PN"1"6;
%"Q_RES"
"2","(2550,-1500)","0","pure_quanta","I43";
;
PART_NUMBER"CS61002FB02"
VALUE"10M"
TOLERANCE"1%"
ROOM"E1S1_P3V3_BOM1"
MATERIAL"CHIP"
PACK_TYPE"0402LF"
WATTAGE"1/16W"
LOCATION"PR4527"
CDS_LIB"pure_quanta"
$SEC"1"
CDS_SEC"1";
"A"
$PN"1"6;
"B"
$PN"2"41;
%"Q_RES"
"1","(2975,-1825)","0","pure_quanta","I44";
;
PART_NUMBER"CS00002JB13"
VALUE"0"
TOLERANCE"5%"
PACK_TYPE"0402LF"
WATTAGE"1/16W"
MATERIAL"CHIP"
ROOM"E1S1_P3V3_BOM1"
$LOCATION"R3973"
CDS_LIB"pure_quanta"
CDS_LOCATION"R3973"
$SEC"1"
CDS_SEC"1";
"B"
$PN"2"40;
"A"
$PN"1"42;
%"Q_CAP"
"1","(3025,-1725)","1","pure_quanta","I45";
;
PART_NUMBER"CH2686K1B01"
VALUE"6800PF"
PACK_TYPE"C0402"
ROOM"E1S1_P3V3_BOM1"
VOLTAGE"50V"
LOCATION"PC2216"
TOLERANCE"10%"
MATERIAL"X7R"
CDS_LIB"pure_quanta"
$SEC"1"
CDS_SEC"1";
"B"
$PN"2"21;
"A"
$PN"1"41;
%"SCHOTTKY_AC"
"1","(2700,-875)","1","pure_quanta","I46";
;
PART_NUMBER"BC000340Z30"
VALUE"B340A-13-F"
MATERIAL"IC"
LOCATION"PD113"
PART_TYPE"SMLF"
CDS_LMAN_SYM_OUTLINE"-75,50,75,-50"
CDS_LIB"pure_quanta"
NEEDS_NO_SIZE"TRUE"
$SEC"1"
CDS_SEC"1";
"C"
$PN"C"6;
"A"
$PN"A"22;
%"GND"
"1","(3150,-1775)","0","logical_power","I47";
;
HDL_POWER"GND"
CDS_LIB"logical_power"
SIZE"1B";
"A<SIZE-1..0>\NAC"21;
%"Q_RES"
"2","(3325,-1525)","0","pure_quanta","I48";
;
PART_NUMBER"CS41002FB09"
TOLERANCE"1%"
VALUE"100K"
WATTAGE"1/16W"
ROOM"E1S1_P3V3_BOM1"
MATERIAL"CHIP"
PACK_TYPE"0402LF"
LOCATION"R3977"
CDS_LIB"pure_quanta"
$SEC"1"
CDS_SEC"1";
"A"
$PN"1"5;
"B"
$PN"2"44;
%"VCCAUX15"
"1","(3525,-1200)","0","logical_power","I49";
;
HDL_POWER"P3V3_AUX"
CDS_LIB"logical_power";
"A"5;
%"GND"
"1","(-2475,-2350)","0","logical_power","I5";
;
SIZE"1B"
HDL_POWER"GND"
CDS_LIB"logical_power";
"A<SIZE-1..0>\NAC"10;
%"Q_RES"
"2","(3725,-1525)","0","pure_quanta","I50";
;
PART_NUMBER"CS41002FB09"
VALUE"100K"
TOLERANCE"1%"
WATTAGE"1/16W"
MATERIAL"CHIP"
PACK_TYPE"0402LF"
ROOM"E1S1_P3V3_BOM1"
LOCATION"R3979"
CDS_LIB"pure_quanta"
$SEC"1"
CDS_SEC"1";
"A"
$PN"1"5;
"B"
$PN"2"40;
%"GND"
"1","(3775,-1200)","0","logical_power","I51";
;
CDS_LIB"logical_power"
HDL_POWER"GND"
SIZE"1B";
"A<SIZE-1..0>\NAC"22;
%"Q_CAP"
"1","(3200,-900)","0","pure_quanta","I52";
;
PART_NUMBER"CH4104K1B00"
VALUE"0.1UF"
VOLTAGE"25V"
PACK_TYPE"0402"
MATERIAL"X7R"
LOCATION"PC2218"
TOLERANCE"10%"
CDS_LIB"pure_quanta"
$SEC"1"
CDS_SEC"1";
"B"
$PN"2"22;
"A"
$PN"1"6;
%"Q_CAP"
"1","(3775,-900)","0","pure_quanta","I53";
;
PART_NUMBER"CH6103KEA01"
VOLTAGE"16V"
VALUE"10UF"
PACK_TYPE"C0805"
MATERIAL"X6S"
LOCATION"PC2220"
CDS_LIB"pure_quanta"
TOLERANCE"10%"
$SEC"1"
CDS_SEC"1";
"B"
$PN"2"22;
"A"
$PN"1"6;
%"UNIVERSAL_POWER"
"1","(3775,-600)","2","logical_power","I54";
;
HDL_POWER"P3V3_E1S_0_R"
CDS_LIB"logical_power";
"A"6;
%"UNIVERSAL_POWER"
"1","(3750,-575)","2","logical_power","I55";
;
HDL_POWER"P3V3_E1S_0_R"
CDS_LIB"logical_power";
"A"0;
%"GND"
"1","(175,825)","0","logical_power","I56";
;
CDS_LIB"logical_power"
SIZE"1B"
HDL_POWER"GND";
"A<SIZE-1..0>\NAC"23;
%"Q_CAP"
"1","(400,900)","1","pure_quanta","I57";
;
PART_NUMBER"CH5104KEB02"
VOLTAGE"25V"
PACK_TYPE"C0402"
MATERIAL"EMPTY"
VALUE"1UF"
ROOM"E1S1_P12V_MAM_MAM_BOM1"
LOCATION"PC2211"
ROOM1"E1S1_P12V_MAM_TIC_BOM2"
CDS_LIB"pure_quanta"
TOLERANCE"10%"
$SEC"1"
CDS_SEC"1";
"B"
$PN"2"37;
"A"
$PN"1"23;
%"GND"
"1","(700,100)","0","logical_power","I58";
;
CDS_LIB"logical_power"
SIZE"1B"
HDL_POWER"GND";
"A<SIZE-1..0>\NAC"24;
%"Q_RES"
"2","(700,400)","0","pure_quanta","I59";
;
PART_NUMBER"CS29312FB02"
PACK_TYPE"0402LF"
TOLERANCE"1%"
VALUE"9.31K"
MATERIAL"EMPTY"
WATTAGE"1/16W"
ROOM"E1S1_P12V_MAM_MAM_BOM1"
LOCATION"PR3968"
ROOM1"E1S1_P12V_MAM_TIC_BOM2"
CDS_LIB"pure_quanta"
$SEC"1"
CDS_SEC"1";
"A"
$PN"1"39;
"B"
$PN"2"24;
%"Q_RES"
"2","(-3150,-1775)","0","pure_quanta","I6";
;
PART_NUMBER"CS31002FB08"
VALUE"10K"
TOLERANCE"1%"
PACK_TYPE"0402LF"
WATTAGE"1/16W"
MATERIAL"CHIP"
ROOM"E1S1_P3V3_BOM1"
$LOCATION"R4072"
CDS_LIB"pure_quanta"
CDS_LOCATION"R4072"
$SEC"1"
CDS_SEC"1";
"A"
$PN"1"1;
"B"
$PN"2"55;
%"Q_CAP"
"1","(175,1200)","0","pure_quanta","I60";
;
PART_NUMBER"CH5104KEB02"
VALUE"1UF"
VOLTAGE"25V"
PACK_TYPE"C0402"
MATERIAL"EMPTY"
ROOM"E1S1_P12V_MAM_MAM_BOM1"
LOCATION"PC2209"
ROOM1"E1S1_P12V_MAM_TIC_BOM2"
CDS_LIB"pure_quanta"
TOLERANCE"10%"
$SEC"1"
CDS_SEC"1";
"B"
$PN"2"23;
"A"
$PN"1"38;
%"Q_RES"
"2","(175,1625)","0","pure_quanta","I61";
;
PART_NUMBER"CS01002FB07"
TOLERANCE"1%"
VALUE"10"
WATTAGE"1/16W"
MATERIAL"EMPTY"
ROOM"E1S1_P12V_MAM_MAM_BOM1"
PACK_TYPE"0402LF"
LOCATION"PR3966"
ROOM1"E1S1_P12V_MAM_TIC_BOM2"
CDS_LIB"pure_quanta"
$SEC"1"
CDS_SEC"1";
"A"
$PN"1"4;
"B"
$PN"2"38;
%"MAX15090BEWIT"
"1","(1450,900)","0","pure_quanta","I62";
;
PART_NUMBER"AL015080B00"
PART_TYPE"SMLF"
VALUE"MAX15090BEWI+T"
ROOM"E1S1_P12V_MAM_MAM_BOM1"
MATERIAL"EMPTY"
LOCATION"PU294"
ROOM1"E1S1_P12V_MAM_TIC_BOM2"
PIN_NAMES_ROTATE"TRUE"
CDS_LIB"pure_quanta"
CDS_LMAN_SYM_OUTLINE"-250,550,250,-550"
$SEC"1"
CDS_SEC"1";
"PG"
$PN"D7"35;
"FAULT# \B"
$PN"C7"36;
"GND_C2"
$PN"C2"25;
"GND_C1"
$PN"C1"25;
"GND_B2"
$PN"B2"25;
"CDLY"
$PN"A7"25;
"GATE"
$PN"A6"34;
"OUT_D6"
$PN"D6"8;
"OUT_D4"
$PN"D4"8;
"OUT_C6"
$PN"C6"8;
"OUT_C4"
$PN"C4"8;
"OUT_B6"
$PN"B6"8;
"OUT_B4"
$PN"B4"8;
"OUT_A4"
$PN"A4"8;
"ISENSE"
$PN"A1"33;
"OV"
$PN"D3"28;
"UV"
$PN"D2"29;
"REG"
$PN"D1"37;
"EN# \B"
$PN"B7"24;
"CB"
$PN"B1"39;
"IN_D5"
$PN"D5"4;
"IN_C5"
$PN"C5"4;
"IN_C3"
$PN"C3"4;
"IN_B5"
$PN"B5"4;
"IN_B3"
$PN"B3"4;
"IN_A5"
$PN"A5"4;
"IN_A3"
$PN"A3"4;
"VCC"
$PN"A2"38;
%"GND"
"1","(2175,225)","0","logical_power","I63";
;
SIZE"1B"
CDS_LIB"logical_power"
HDL_POWER"GND";
"A<SIZE-1..0>\NAC"25;
%"Q_RES"
"2","(2300,525)","0","pure_quanta","I64";
;
PART_NUMBER"CS22672FB03"
TOLERANCE"1%"
VALUE"2.67K"
WATTAGE"1/16W"
MATERIAL"EMPTY"
PACK_TYPE"0402LF"
ROOM"E1S1_P12V_MAM_MAM_BOM1"
LOCATION"PR3970"
ROOM1"E1S1_P12V_MAM_TIC_BOM2"
CDS_LIB"pure_quanta"
$SEC"1"
CDS_SEC"1";
"A"
$PN"1"33;
"B"
$PN"2"25;
%"Q_RES"
"1","(3075,475)","0","pure_quanta","I65";
;
PART_NUMBER"CS00002JB13"
WATTAGE"1/16W"
MATERIAL"EMPTY"
VALUE"0"
ROOM1"E1S1_P12V_MAM_TIC_BOM2"
TOLERANCE"5%"
PACK_TYPE"0402LF"
$LOCATION"R3975"
CDS_LIB"pure_quanta"
CDS_LOCATION"R3975"
$SEC"1"
CDS_SEC"1";
"B"
$PN"2"30;
"A"
$PN"1"33;
%"Q_CAP"
"1","(2800,1000)","1","pure_quanta","I66";
;
PART_NUMBER"CH23906KB14"
VALUE"3900PF"
MATERIAL"EMPTY"
VOLTAGE"50V"
ROOM"E1S1_P12V_MAM_MAM_BOM1"
PACK_TYPE"C0402"
LOCATION"PC2215"
ROOM1"E1S1_P12V_MAM_TIC_BOM2"
CDS_LIB"pure_quanta"
TOLERANCE"10%"
$SEC"1"
CDS_SEC"1";
"B"
$PN"2"26;
"A"
$PN"1"34;
%"Q_RES"
"1","(3075,700)","0","pure_quanta","I67";
;
PART_NUMBER"CS00002JB13"
WATTAGE"1/16W"
MATERIAL"EMPTY"
VALUE"0"
TOLERANCE"5%"
PACK_TYPE"0402LF"
ROOM"E1S1_P12V_MAM_MAM_BOM1"
LOCATION"R3974"
CDS_LIB"pure_quanta"
$SEC"1"
CDS_SEC"1";
"B"
$PN"2"31;
"A"
$PN"1"33;
%"Q_RES"
"1","(2925,900)","0","pure_quanta","I68";
;
PART_NUMBER"CS00002JB13"
MATERIAL"EMPTY"
VALUE"0"
TOLERANCE"5%"
PACK_TYPE"0402LF"
ROOM"E1S1_P12V_MAM_MAM_BOM1"
WATTAGE"1/16W"
$LOCATION"R3972"
ROOM1"E1S1_P12V_MAM_TIC_BOM2"
CDS_LIB"pure_quanta"
CDS_LOCATION"R3972"
$SEC"1"
CDS_SEC"1";
"B"
$PN"2"32;
"A"
$PN"1"35;
%"Q_CAP"
"1","(2250,1225)","0","pure_quanta","I69";
;
PART_NUMBER"CH31006KB18"
PACK_TYPE"C0402"
VALUE"0.01UF"
VOLTAGE"50V"
MATERIAL"EMPTY"
LOCATION"PC2214"
CDS_LIB"pure_quanta"
TOLERANCE"10%"
$SEC"1"
CDS_SEC"1";
"B"
$PN"2"34;
"A"
$PN"1"8;
%"UNIVERSAL_POWER"
"1","(-3150,-1525)","0","logical_power","I7";
;
HDL_POWER"P12V_AUX"
CDS_LIB"logical_power";
"A"1;
%"Q_RES"
"2","(2575,1250)","0","pure_quanta","I70";
;
PART_NUMBER"CS61002FB02"
VALUE"10M"
MATERIAL"EMPTY"
PACK_TYPE"0402LF"
WATTAGE"1/16W"
ROOM"E1S1_P12V_MAM_MAM_BOM1"
TOLERANCE"1%"
LOCATION"PR4528"
ROOM1"E1S1_P12V_MAM_TIC_BOM2"
CDS_LIB"pure_quanta"
$SEC"1"
CDS_SEC"1";
"A"
$PN"1"8;
"B"
$PN"2"34;
%"SCHOTTKY_AC"
"1","(2675,1850)","1","pure_quanta","I71";
;
PART_NUMBER"BC000340Z30"
MATERIAL"IC"
VALUE"B340A-13-F"
LOCATION"PD112"
NEEDS_NO_SIZE"TRUE"
CDS_LMAN_SYM_OUTLINE"-75,50,75,-50"
CDS_LIB"pure_quanta"
PART_TYPE"SMLF"
$SEC"1"
CDS_SEC"1";
"C"
$PN"C"8;
"A"
$PN"A"27;
%"GND"
"1","(3050,950)","0","logical_power","I72";
;
CDS_LIB"logical_power"
SIZE"1B"
HDL_POWER"GND";
"A<SIZE-1..0>\NAC"26;
%"Q_RES"
"2","(3275,1150)","0","pure_quanta","I73";
;
PART_NUMBER"CS41002FB09"
PACK_TYPE"0402LF"
TOLERANCE"1%"
MATERIAL"EMPTY"
WATTAGE"1/16W"
VALUE"100K"
ROOM"E1S1_P12V_MAM_MAM_BOM1"
LOCATION"R3976"
ROOM1"E1S1_P12V_MAM_TIC_BOM2"
CDS_LIB"pure_quanta"
$SEC"1"
CDS_SEC"1";
"A"
$PN"1"7;
"B"
$PN"2"36;
%"VCCAUX15"
"1","(3475,1500)","0","logical_power","I74";
;
HDL_POWER"P3V3_AUX"
CDS_LIB"logical_power";
"A"7;
%"Q_CAP"
"1","(3150,1825)","0","pure_quanta","I75";
;
PART_NUMBER"CH4104K1B00"
PACK_TYPE"0402"
VOLTAGE"25V"
MATERIAL"X7R"
VALUE"0.1UF"
LOCATION"PC2217"
CDS_LIB"pure_quanta"
TOLERANCE"10%"
$SEC"1"
CDS_SEC"1";
"B"
$PN"2"27;
"A"
$PN"1"8;
%"Q_RES"
"2","(3700,1150)","0","pure_quanta","I76";
;
PART_NUMBER"CS41002FB09"
PACK_TYPE"0402LF"
VALUE"100K"
TOLERANCE"1%"
MATERIAL"EMPTY"
WATTAGE"1/16W"
ROOM"E1S1_P12V_MAM_MAM_BOM1"
LOCATION"R3978"
ROOM1"E1S1_P12V_MAM_TIC_BOM2"
CDS_LIB"pure_quanta"
$SEC"1"
CDS_SEC"1";
"A"
$PN"1"7;
"B"
$PN"2"32;
%"GND"
"1","(3975,1525)","0","logical_power","I77";
;
SIZE"1B"
CDS_LIB"logical_power"
HDL_POWER"GND";
"A<SIZE-1..0>\NAC"27;
%"Q_CAP"
"1","(3575,1825)","0","pure_quanta","I78";
;
PART_NUMBER"CH6103KEA03"
VOLTAGE"16V"
MATERIAL"X6S"
VALUE"10UF"
PACK_TYPE"C0805"
LOCATION"PC2219"
CDS_LIB"pure_quanta"
TOLERANCE"10%"
$SEC"1"
CDS_SEC"1";
"B"
$PN"2"27;
"A"
$PN"1"8;
%"Q_CAP"
"1","(3975,1825)","0","pure_quanta","I79";
;
PART_NUMBER"CH6103KEA03"
VOLTAGE"16V"
VALUE"10UF"
MATERIAL"X6S"
PACK_TYPE"C0805"
LOCATION"PC2280"
CDS_LIB"pure_quanta"
TOLERANCE"10%"
$SEC"1"
CDS_SEC"1";
"B"
$PN"2"27;
"A"
$PN"1"8;
%"GND"
"1","(-3025,-450)","0","logical_power","I8";
;
HDL_POWER"GND"
CDS_LIB"logical_power"
SIZE"1B";
"A<SIZE-1..0>\NAC"11;
%"UNIVERSAL_POWER"
"1","(3975,2125)","2","logical_power","I80";
;
HDL_POWER"P12V_E1S_0"
CDS_LIB"logical_power";
"A"8;
%"DIODE_TVS"
"1","(-925,1625)","1","pure_quanta","I84";
;
PART_NUMBER"BCSMF14AZ01"
MATERIAL"IC"
VALUE"SMF14A"
LOCATION"PD114"
CDS_LIB"pure_quanta"
CDS_LMAN_SYM_OUTLINE"-100,50,100,-50"
PIN_NAMES_ROTATE"TRUE"
PART_TYPE"SMLF"
$SEC"1"
CDS_SEC"1";
"C"
$PN"C"
Pin_Length"Short"4;
"A"
$PN"A"17;
%"Q_RES"
"2","(-150,650)","0","pure_quanta","I85";
;
PART_NUMBER"CS26802FB02"
MATERIAL"EMPTY"
TOLERANCE"1%"
VALUE"6.8K"
WATTAGE"1/16W"
PACK_TYPE"0402LF"
ROOM"E1S1_P12V_MAM_MAM_BOM1"
LOCATION"PR3961"
ROOM1"E1S1_P12V_MAM_TIC_BOM2"
CDS_LIB"pure_quanta"
$SEC"1"
CDS_SEC"1";
"A"
$PN"1"29;
"B"
$PN"2"28;
%"Q_RES"
"2","(-3025,-225)","0","pure_quanta","I9";
;
PART_NUMBER"CS24702JB10"
PACK_TYPE"0402LF"
WATTAGE"1/16W"
MATERIAL"CHIP"
TOLERANCE"5%"
VALUE"4.7K"
$LOCATION"R4073"
CDS_LIB"pure_quanta"
CDS_LOCATION"R4073"
$SEC"1"
CDS_SEC"1";
"A"
$PN"1"51;
"B"
$PN"2"11;
END.
